(kicad_pcb
	(version 20260206)
	(generator "pcbnew")
	(generator_version "10.0")
	(general
		(thickness 1.6)
		(legacy_teardrops no)
	)
	(paper "A4")
	(title_block
		(title "dpb — 14545-sa.0730WZS0815.brd")
		(comment 1 "Honey Badger (Wiwynn) / footprints 758-764 of 1066")
	)
	(layers
		(0 "F.Cu" signal "TOP")
		(4 "In1.Cu" signal "L2GND")
		(6 "In2.Cu" signal "L3")
		(8 "In3.Cu" signal "L4VCC")
		(10 "In4.Cu" signal "L5VCC")
		(12 "In5.Cu" signal "L6")
		(14 "In6.Cu" signal "L7GND")
		(2 "B.Cu" signal "BOTTOM")
		(9 "F.Adhes" user "F.Adhesive")
		(11 "B.Adhes" user "B.Adhesive")
		(13 "F.Paste" user "Package Geometry/Pastemask Top")
		(15 "B.Paste" user "Package Geometry/Pastemask Bottom")
		(5 "F.SilkS" user "Ref Des/Silkscreen Top")
		(7 "B.SilkS" user "Ref Des/Silkscreen Bottom")
		(1 "F.Mask" user "Board Geometry/Soldermask Top")
		(3 "B.Mask" user "Board Geometry/Soldermask Bottom")
		(17 "Dwgs.User" user "User.Drawings")
		(19 "Cmts.User" user "User.Comments")
		(21 "Eco1.User" user "User.Eco1")
		(23 "Eco2.User" user "User.Eco2")
		(25 "Edge.Cuts" user "Board Geometry/Outline")
		(27 "Margin" user)
		(31 "F.CrtYd" user "Package Geometry/Place Bound Top")
		(29 "B.CrtYd" user "Package Geometry/Place Bound Bottom")
		(35 "F.Fab" user "Ref Des/Assembly Top")
		(33 "B.Fab" user "Ref Des/Assembly Bottom")
	)
	(footprint ""
		(layer "F.Cu")
		(at 60.832746 -19.4437 90)
		(property "Reference" "PR19"
			(at 0 0 90)
			(layer "F.SilkS")
			(hide yes)
			(effects
				(font
					(size 1.27 1.27)
				)
			)
		)
		(property "Value" "0R3J-0-U-GP"
			(at -0.0254 -2.5146 90)
			(unlocked yes)
			(layer "F.Fab")
			(hide yes)
			(effects
				(font
					(size 1.016 1.016)
					(thickness 0.1524)
				)
			)
		)
		(property "Device Type" "R603H22"
			(at -0.0254 -4.0386 90)
			(unlocked yes)
			(layer "F.Fab")
			(hide yes)
			(effects
				(font
					(size 1.016 1.016)
					(thickness 0.1524)
				)
			)
		)
		(duplicate_pad_numbers_are_jumpers no)
		(fp_line
			(start 0.2032 0)
			(end 0.4826 0)
			(stroke
				(width 0.2032)
				(type default)
			)
			(layer "F.SilkS")
		)
		(fp_line
			(start -0.4826 0)
			(end -0.2032 0)
			(stroke
				(width 0.2032)
				(type default)
			)
			(layer "F.SilkS")
		)
		(fp_rect
			(start -0.5842 1.3335)
			(end 0.5842 -1.3335)
			(stroke
				(width 0)
				(type default)
			)
			(fill no)
			(layer "F.CrtYd")
		)
		(fp_rect
			(start -0.5842 1.3335)
			(end 0.5842 -1.3335)
			(stroke
				(width 0)
				(type default)
			)
			(fill no)
			(layer "F.Fab")
		)
		(pad "1" smd custom
			(at 0 -0.762 90)
			(size 0.2159 0.2159)
			(layers "F.Cu" "F.Mask" "F.Paste")
			(net "P5VB_12VIN")
			(options
				(clearance outline)
				(anchor circle)
			)
			(primitives
				(gr_poly
					(pts
						(arc
							(start -0.3302 -0.4318)
							(mid -0.402042 -0.402042)
							(end -0.4318 -0.3302)
						)
						(arc
							(start -0.4318 0.3302)
							(mid -0.402042 0.402042)
							(end -0.3302 0.4318)
						)
						(arc
							(start 0.3302 0.4318)
							(mid 0.402042 0.402042)
							(end 0.4318 0.3302)
						)
						(arc
							(start 0.4318 -0.3302)
							(mid 0.402042 -0.402042)
							(end 0.3302 -0.4318)
						)
					)
					(width 0)
					(fill yes)
				)
			)
		)
		(pad "2" smd custom
			(at 0 0.762 90)
			(size 0.2159 0.2159)
			(layers "F.Cu" "F.Mask" "F.Paste")
			(net "P5VB_VDD")
			(options
				(clearance outline)
				(anchor circle)
			)
			(primitives
				(gr_poly
					(pts
						(arc
							(start -0.3302 -0.4318)
							(mid -0.402042 -0.402042)
							(end -0.4318 -0.3302)
						)
						(arc
							(start -0.4318 0.3302)
							(mid -0.402042 0.402042)
							(end -0.3302 0.4318)
						)
						(arc
							(start 0.3302 0.4318)
							(mid 0.402042 0.402042)
							(end 0.4318 0.3302)
						)
						(arc
							(start 0.4318 -0.3302)
							(mid 0.402042 -0.402042)
							(end 0.3302 -0.4318)
						)
					)
					(width 0)
					(fill yes)
				)
			)
		)
	)
	(footprint ""
		(layer "F.Cu")
		(at 43.941746 -232.692702 -90)
		(property "Reference" "R274"
			(at 0 0 270)
			(layer "F.SilkS")
			(hide yes)
			(effects
				(font
					(size 1.27 1.27)
				)
			)
		)
		(property "Value" "4K7R2J-2-GP"
			(at 0.064008 -3.993896 270)
			(unlocked yes)
			(layer "F.Fab")
			(hide yes)
			(effects
				(font
					(size 1.016 1.016)
					(thickness 0.1524)
				)
			)
		)
		(property "Device Type" "R402H16"
			(at 0.064008 -5.517896 270)
			(unlocked yes)
			(layer "F.Fab")
			(hide yes)
			(effects
				(font
					(size 1.016 1.016)
					(thickness 0.1524)
				)
			)
		)
		(duplicate_pad_numbers_are_jumpers no)
		(fp_line
			(start -0.508 -0.9398)
			(end -0.508 0.9398)
			(stroke
				(width 0.1524)
				(type default)
			)
			(layer "F.SilkS")
		)
		(fp_line
			(start 0.508 -0.9398)
			(end -0.508 -0.9398)
			(stroke
				(width 0.1524)
				(type default)
			)
			(layer "F.SilkS")
		)
		(fp_rect
			(start -0.508 0.9398)
			(end 0.508 -0.9398)
			(stroke
				(width 0)
				(type default)
			)
			(fill no)
			(layer "F.CrtYd")
		)
		(fp_rect
			(start -0.508 0.9398)
			(end 0.508 -0.9398)
			(stroke
				(width 0)
				(type default)
			)
			(fill no)
			(layer "F.Fab")
		)
		(pad "1" smd custom
			(at 0 -0.4445 270)
			(size 0.1397 0.1397)
			(layers "F.Cu" "F.Mask" "F.Paste")
			(net "P3V3")
			(options
				(clearance outline)
				(anchor circle)
			)
			(primitives
				(gr_poly
					(pts
						(arc
							(start -0.1778 -0.2794)
							(mid -0.249642 -0.249642)
							(end -0.2794 -0.1778)
						)
						(arc
							(start -0.2794 0.1778)
							(mid -0.249642 0.249642)
							(end -0.1778 0.2794)
						)
						(arc
							(start 0.1778 0.2794)
							(mid 0.249642 0.249642)
							(end 0.2794 0.1778)
						)
						(arc
							(start 0.2794 -0.1778)
							(mid 0.249642 -0.249642)
							(end 0.1778 -0.2794)
						)
					)
					(width 0)
					(fill yes)
				)
			)
		)
		(pad "2" smd custom
			(at 0 0.4445 270)
			(size 0.1397 0.1397)
			(layers "F.Cu" "F.Mask" "F.Paste")
			(net "HDD_PRSNT_NET12")
			(options
				(clearance outline)
				(anchor circle)
			)
			(primitives
				(gr_poly
					(pts
						(arc
							(start -0.1778 -0.2794)
							(mid -0.249642 -0.249642)
							(end -0.2794 -0.1778)
						)
						(arc
							(start -0.2794 0.1778)
							(mid -0.249642 0.249642)
							(end -0.1778 0.2794)
						)
						(arc
							(start 0.1778 0.2794)
							(mid 0.249642 0.249642)
							(end 0.2794 0.1778)
						)
						(arc
							(start 0.2794 -0.1778)
							(mid 0.249642 -0.249642)
							(end 0.1778 -0.2794)
						)
					)
					(width 0)
					(fill yes)
				)
			)
		)
	)
	(footprint ""
		(layer "F.Cu")
		(at 28.701746 -278.5237 -90)
		(property "Reference" "U24"
			(at 0 0 270)
			(layer "F.SilkS")
			(hide yes)
			(effects
				(font
					(size 1.27 1.27)
				)
			)
		)
		(property "Value" "74LVC1G08GW-1-GP"
			(at -2.3368 -8.6868 270)
			(unlocked yes)
			(layer "F.Fab")
			(hide yes)
			(effects
				(font
					(size 1.016 1.016)
					(thickness 0.1524)
				)
			)
		)
		(property "Device Type" "SC70-5H44"
			(at -2.3114 -10.414 270)
			(unlocked yes)
			(layer "F.Fab")
			(hide yes)
			(effects
				(font
					(size 1.016 1.016)
					(thickness 0.1524)
				)
			)
		)
		(duplicate_pad_numbers_are_jumpers no)
		(fp_line
			(start -1.27 1.7018)
			(end -1.27 -1.7018)
			(stroke
				(width 0.1524)
				(type default)
			)
			(layer "F.SilkS")
		)
		(fp_line
			(start 1.27 1.7018)
			(end -1.27 1.7018)
			(stroke
				(width 0.1524)
				(type default)
			)
			(layer "F.SilkS")
		)
		(fp_line
			(start -1.27 -1.7018)
			(end 1.27 -1.7018)
			(stroke
				(width 0.1524)
				(type default)
			)
			(layer "F.SilkS")
		)
		(fp_line
			(start 1.27 -1.7018)
			(end 1.27 1.7018)
			(stroke
				(width 0.1524)
				(type default)
			)
			(layer "F.SilkS")
		)
		(fp_line
			(start 0.6604 -1.8034)
			(end 1.3843 -1.8034)
			(stroke
				(width 0.3302)
				(type default)
			)
			(layer "F.SilkS")
		)
		(fp_line
			(start 1.3843 -1.8034)
			(end 1.3843 -1.1176)
			(stroke
				(width 0.3302)
				(type default)
			)
			(layer "F.SilkS")
		)
		(fp_rect
			(start -1.524 1.9558)
			(end 1.524 -1.9558)
			(stroke
				(width 0)
				(type default)
			)
			(fill no)
			(layer "F.CrtYd")
		)
		(fp_poly
			(pts
				(xy -1.524 -1.9558) (xy 1.524 -1.9558) (xy 1.524 1.9558) (xy -1.524 1.9558)
			)
			(stroke
				(width 0)
				(type default)
			)
			(fill no)
			(layer "F.Fab")
		)
		(pad "1" smd rect
			(at 0.65024 -0.8255 270)
			(size 0.4064 1.2192)
			(layers "F.Cu" "F.Mask" "F.Paste")
			(net "SAS_EXP_B_PWR7")
		)
		(pad "2" smd rect
			(at 0 -0.8255 270)
			(size 0.4064 1.2192)
			(layers "F.Cu" "F.Mask" "F.Paste")
			(net "SAS_EXP_A_PWR7")
		)
		(pad "3" smd rect
			(at -0.65024 -0.8255 270)
			(size 0.4064 1.2192)
			(layers "F.Cu" "F.Mask" "F.Paste")
			(net "GND")
		)
		(pad "4" smd rect
			(at -0.65024 0.8255 270)
			(size 0.4064 1.2192)
			(layers "F.Cu" "F.Mask" "F.Paste")
			(net "DRIVE_PWR7")
		)
		(pad "5" smd rect
			(at 0.65024 0.8255 270)
			(size 0.4064 1.2192)
			(layers "F.Cu" "F.Mask" "F.Paste")
			(net "P3V3")
		)
	)
	(footprint ""
		(layer "F.Cu")
		(at 14.715744 -259.3467 -90)
		(property "Reference" "R270"
			(at 0 0 270)
			(layer "F.SilkS")
			(hide yes)
			(effects
				(font
					(size 1.27 1.27)
				)
			)
		)
		(property "Value" "0R2J-2-GP"
			(at 0.064008 -3.993896 270)
			(unlocked yes)
			(layer "F.Fab")
			(hide yes)
			(effects
				(font
					(size 1.016 1.016)
					(thickness 0.1524)
				)
			)
		)
		(property "Device Type" "R402H16"
			(at 0.064008 -5.517896 270)
			(unlocked yes)
			(layer "F.Fab")
			(hide yes)
			(effects
				(font
					(size 1.016 1.016)
					(thickness 0.1524)
				)
			)
		)
		(duplicate_pad_numbers_are_jumpers no)
		(fp_line
			(start -0.508 -0.9398)
			(end -0.508 0.9398)
			(stroke
				(width 0.1524)
				(type default)
			)
			(layer "F.SilkS")
		)
		(fp_line
			(start 0.508 -0.9398)
			(end -0.508 -0.9398)
			(stroke
				(width 0.1524)
				(type default)
			)
			(layer "F.SilkS")
		)
		(fp_rect
			(start -0.508 0.9398)
			(end 0.508 -0.9398)
			(stroke
				(width 0)
				(type default)
			)
			(fill no)
			(layer "F.CrtYd")
		)
		(fp_rect
			(start -0.508 0.9398)
			(end 0.508 -0.9398)
			(stroke
				(width 0)
				(type default)
			)
			(fill no)
			(layer "F.Fab")
		)
		(pad "1" smd custom
			(at 0 -0.4445 270)
			(size 0.1397 0.1397)
			(layers "F.Cu" "F.Mask" "F.Paste")
			(net "DRV_ACT_NET12")
			(options
				(clearance outline)
				(anchor circle)
			)
			(primitives
				(gr_poly
					(pts
						(arc
							(start -0.1778 -0.2794)
							(mid -0.249642 -0.249642)
							(end -0.2794 -0.1778)
						)
						(arc
							(start -0.2794 0.1778)
							(mid -0.249642 0.249642)
							(end -0.1778 0.2794)
						)
						(arc
							(start 0.1778 0.2794)
							(mid 0.249642 0.249642)
							(end 0.2794 0.1778)
						)
						(arc
							(start 0.2794 -0.1778)
							(mid 0.249642 -0.249642)
							(end 0.1778 -0.2794)
						)
					)
					(width 0)
					(fill yes)
				)
			)
		)
		(pad "2" smd custom
			(at 0 0.4445 270)
			(size 0.1397 0.1397)
			(layers "F.Cu" "F.Mask" "F.Paste")
			(net "DRIVE_ACT_12")
			(options
				(clearance outline)
				(anchor circle)
			)
			(primitives
				(gr_poly
					(pts
						(arc
							(start -0.1778 -0.2794)
							(mid -0.249642 -0.249642)
							(end -0.2794 -0.1778)
						)
						(arc
							(start -0.2794 0.1778)
							(mid -0.249642 0.249642)
							(end -0.1778 0.2794)
						)
						(arc
							(start 0.1778 0.2794)
							(mid 0.249642 0.249642)
							(end 0.2794 0.1778)
						)
						(arc
							(start 0.2794 -0.1778)
							(mid 0.249642 -0.249642)
							(end 0.1778 -0.2794)
						)
					)
					(width 0)
					(fill yes)
				)
			)
		)
	)
	(footprint ""
		(layer "F.Cu")
		(at 166.509446 -457.742036)
		(property "Reference" "C353"
			(at 0 0 0)
			(layer "F.SilkS")
			(hide yes)
			(effects
				(font
					(size 1.27 1.27)
				)
			)
		)
		(property "Value" "SCD1U16V2KX-3GP"
			(at 1.1811 -2.7051 0)
			(unlocked yes)
			(layer "F.Fab")
			(hide yes)
			(effects
				(font
					(size 1.016 1.016)
					(thickness 0.1524)
				)
			)
		)
		(property "Device Type" "C402H22"
			(at 1.1811 -4.2291 0)
			(unlocked yes)
			(layer "F.Fab")
			(hide yes)
			(effects
				(font
					(size 1.016 1.016)
					(thickness 0.1524)
				)
			)
		)
		(duplicate_pad_numbers_are_jumpers no)
		(fp_rect
			(start -0.4318 0.9525)
			(end 0.4318 -0.9525)
			(stroke
				(width 0)
				(type default)
			)
			(fill no)
			(layer "F.CrtYd")
		)
		(fp_rect
			(start -0.4318 0.9525)
			(end 0.4318 -0.9525)
			(stroke
				(width 0)
				(type default)
			)
			(fill no)
			(layer "F.Fab")
		)
		(pad "1" smd custom
			(at 0 -0.4445)
			(size 0.1524 0.1524)
			(layers "F.Cu" "F.Mask" "F.Paste")
			(net "P5VA_SENSE")
			(options
				(clearance outline)
				(anchor circle)
			)
			(primitives
				(gr_poly
					(pts
						(arc
							(start 0.3048 -0.2032)
							(mid 0.275042 -0.275042)
							(end 0.2032 -0.3048)
						)
						(arc
							(start -0.2032 -0.3048)
							(mid -0.275042 -0.275042)
							(end -0.3048 -0.2032)
						)
						(arc
							(start -0.3048 0.2032)
							(mid -0.275042 0.275042)
							(end -0.2032 0.3048)
						)
						(arc
							(start 0.2032 0.3048)
							(mid 0.275042 0.275042)
							(end 0.3048 0.2032)
						)
					)
					(width 0)
					(fill yes)
				)
			)
		)
		(pad "2" smd custom
			(at 0 0.4445)
			(size 0.1524 0.1524)
			(layers "F.Cu" "F.Mask" "F.Paste")
			(net "GND")
			(options
				(clearance outline)
				(anchor circle)
			)
			(primitives
				(gr_poly
					(pts
						(arc
							(start 0.3048 -0.2032)
							(mid 0.275042 -0.275042)
							(end 0.2032 -0.3048)
						)
						(arc
							(start -0.2032 -0.3048)
							(mid -0.275042 -0.275042)
							(end -0.3048 -0.2032)
						)
						(arc
							(start -0.3048 0.2032)
							(mid -0.275042 0.275042)
							(end -0.2032 0.3048)
						)
						(arc
							(start 0.2032 0.3048)
							(mid 0.275042 0.275042)
							(end 0.3048 0.2032)
						)
					)
					(width 0)
					(fill yes)
				)
			)
		)
	)
	(footprint ""
		(layer "F.Cu")
		(at 33.893252 -160.92551 -90)
		(property "Reference" "C231"
			(at 0 0 270)
			(layer "F.SilkS")
			(hide yes)
			(effects
				(font
					(size 1.27 1.27)
				)
			)
		)
		(property "Value" "SCD01U50V2KX-1GP"
			(at 1.1811 -2.7051 270)
			(unlocked yes)
			(layer "F.Fab")
			(hide yes)
			(effects
				(font
					(size 1.016 1.016)
					(thickness 0.1524)
				)
			)
		)
		(property "Device Type" "C402H22"
			(at 1.1811 -4.2291 270)
			(unlocked yes)
			(layer "F.Fab")
			(hide yes)
			(effects
				(font
					(size 1.016 1.016)
					(thickness 0.1524)
				)
			)
		)
		(duplicate_pad_numbers_are_jumpers no)
		(fp_rect
			(start -0.4318 0.9525)
			(end 0.4318 -0.9525)
			(stroke
				(width 0)
				(type default)
			)
			(fill no)
			(layer "F.CrtYd")
		)
		(fp_rect
			(start -0.4318 0.9525)
			(end 0.4318 -0.9525)
			(stroke
				(width 0)
				(type default)
			)
			(fill no)
			(layer "F.Fab")
		)
		(pad "1" smd custom
			(at 0 -0.4445 270)
			(size 0.1524 0.1524)
			(layers "F.Cu" "F.Mask" "F.Paste")
			(net "SAS2X28_DRIVE_RX_P_A8")
			(options
				(clearance outline)
				(anchor circle)
			)
			(primitives
				(gr_poly
					(pts
						(arc
							(start 0.3048 -0.2032)
							(mid 0.275042 -0.275042)
							(end 0.2032 -0.3048)
						)
						(arc
							(start -0.2032 -0.3048)
							(mid -0.275042 -0.275042)
							(end -0.3048 -0.2032)
						)
						(arc
							(start -0.3048 0.2032)
							(mid -0.275042 0.275042)
							(end -0.2032 0.3048)
						)
						(arc
							(start 0.2032 0.3048)
							(mid 0.275042 0.275042)
							(end 0.3048 0.2032)
						)
					)
					(width 0)
					(fill yes)
				)
			)
		)
		(pad "2" smd custom
			(at 0 0.4445 270)
			(size 0.1524 0.1524)
			(layers "F.Cu" "F.Mask" "F.Paste")
			(net "SAS2X28_A_HDD8_RX_+")
			(options
				(clearance outline)
				(anchor circle)
			)
			(primitives
				(gr_poly
					(pts
						(arc
							(start 0.3048 -0.2032)
							(mid 0.275042 -0.275042)
							(end 0.2032 -0.3048)
						)
						(arc
							(start -0.2032 -0.3048)
							(mid -0.275042 -0.275042)
							(end -0.3048 -0.2032)
						)
						(arc
							(start -0.3048 0.2032)
							(mid -0.275042 0.275042)
							(end -0.2032 0.3048)
						)
						(arc
							(start 0.2032 0.3048)
							(mid 0.275042 0.275042)
							(end 0.3048 0.2032)
						)
					)
					(width 0)
					(fill yes)
				)
			)
		)
	)
	(footprint ""
		(layer "F.Cu")
		(at 218.1606 -393.9032 180)
		(property "Reference" "C129"
			(at 0 0 180)
			(layer "F.SilkS")
			(hide yes)
			(effects
				(font
					(size 1.27 1.27)
				)
			)
		)
		(property "Value" "SC10U25V6KX-1GP"
			(at -0.0762 -5.1308 180)
			(unlocked yes)
			(layer "F.Fab")
			(hide yes)
			(effects
				(font
					(size 1.016 1.016)
					(thickness 0.1524)
				)
			)
		)
		(property "Device Type" "C1206H71"
			(at -0.127 -6.6548 180)
			(unlocked yes)
			(layer "F.Fab")
			(hide yes)
			(effects
				(font
					(size 1.016 1.016)
					(thickness 0.1524)
				)
			)
		)
		(duplicate_pad_numbers_are_jumpers no)
		(fp_line
			(start 1.016 2.2352)
			(end -1.016 2.2352)
			(stroke
				(width 0.1524)
				(type default)
			)
			(layer "F.SilkS")
		)
		(fp_line
			(start 1.016 0.8382)
			(end 1.016 2.2352)
			(stroke
				(width 0.1524)
				(type default)
			)
			(layer "F.SilkS")
		)
		(fp_line
			(start 1.016 -2.2352)
			(end 1.016 -0.8382)
			(stroke
				(width 0.1524)
				(type default)
			)
			(layer "F.SilkS")
		)
		(fp_line
			(start -1.016 2.2352)
			(end -1.016 0.8382)
			(stroke
				(width 0.1524)
				(type default)
			)
			(layer "F.SilkS")
		)
		(fp_line
			(start -1.016 -0.8382)
			(end -1.016 -2.2352)
			(stroke
				(width 0.1524)
				(type default)
			)
			(layer "F.SilkS")
		)
		(fp_line
			(start -1.016 -2.2352)
			(end 1.016 -2.2352)
			(stroke
				(width 0.1524)
				(type default)
			)
			(layer "F.SilkS")
		)
		(fp_rect
			(start -1.0922 2.3114)
			(end 1.0922 -2.3114)
			(stroke
				(width 0)
				(type default)
			)
			(fill no)
			(layer "F.CrtYd")
		)
		(fp_poly
			(pts
				(xy 1.0922 -2.3114) (xy 1.0922 2.3114) (xy -1.0922 2.3114) (xy -1.0922 -2.3114)
			)
			(stroke
				(width 0)
				(type default)
			)
			(fill no)
			(layer "F.Fab")
		)
		(pad "1" smd rect
			(at 0 -1.397 180)
			(size 1.651 1.27)
			(layers "F.Cu" "F.Mask" "F.Paste")
			(net "P12V_HDD1")
		)
		(pad "2" smd rect
			(at 0 1.397 180)
			(size 1.651 1.27)
			(layers "F.Cu" "F.Mask" "F.Paste")
			(net "GND")
		)
	)
)
